(kicad_pcb
	(version 20221018)
	(generator pcbnew)
	(general
    (thickness 1.656)
  )
	(paper "A4")
	(title_block
    (title "SDI-MIPI Bridge")
    (date "2023-08-09")
    (rev "1.3.4")
    (company "Antmicro")
		(comment 9 "footprints 31-38 of 190")
	)
	(layers
    (0 "F.Cu" signal)
    (1 "In1.Cu" power)
    (2 "In2.Cu" power)
    (3 "In3.Cu" signal)
    (4 "In4.Cu" signal)
    (31 "B.Cu" signal)
    (32 "B.Adhes" user "B.Adhesive")
    (33 "F.Adhes" user "F.Adhesive")
    (34 "B.Paste" user)
    (35 "F.Paste" user)
    (36 "B.SilkS" user "B.Silkscreen")
    (37 "F.SilkS" user "F.Silkscreen")
    (38 "B.Mask" user)
    (39 "F.Mask" user)
    (40 "Dwgs.User" user "User.Drawings")
    (41 "Cmts.User" user "User.Comments")
    (42 "Eco1.User" user "User.Eco1")
    (43 "Eco2.User" user "User.Eco2")
    (44 "Edge.Cuts" user)
    (45 "Margin" user)
    (46 "B.CrtYd" user "B.Courtyard")
    (47 "F.CrtYd" user "F.Courtyard")
    (48 "B.Fab" user)
    (49 "F.Fab" user)
  )
	(footprint "sdi-mipi-bridge-footprints:R_0603_1608Metric" (layer "F.Cu")
    (at 113.35 110.99 90)
    (descr "Resistor SMD 0603")
    (tags "resistor SMD 0603")
    (property "Author" "Antmicro")
    (property "License" "Apache-2.0")
    (property "MPN" "CR0603-FX-75R0ELF")
    (property "Manufacturer" "Bourns")
    (property "Sheetfile" "sdi-mipi-bridge.kicad_sch")
    (property "Sheetname" "")
    (property "Tolerance" "1%")
    (property "Val" "75R")
    (property "ki_description" "75R resistor in 0603 package with 1% tolerance")
    (attr smd)
    (fp_text reference "R28" (at 3.59 0.25 90) (layer "F.SilkS")
        (effects (font (size 0.65 0.65) (thickness 0.15)) (justify right bottom))
    )
    (fp_text value "R_75R_0603" (at 0 1.6 90) (layer "F.Fab") hide
        (effects (font (size 0.7 0.7) (thickness 0.15)) (justify left bottom))
    )
    (fp_text user "Author: Antmicro" (at -1.25 4.9 90) (layer "F.Fab") hide
        (effects (font (size 0.7 0.7) (thickness 0.15)) (justify left bottom))
    )
    (fp_text user "License: Apache-2.0" (at -1.25 5.9 90) (layer "F.Fab") hide
        (effects (font (size 0.7 0.7) (thickness 0.15)) (justify left bottom))
    )
    (fp_text user "${REFERENCE}" (at -1.25 3.898 90) (layer "F.Fab") hide
        (effects (font (size 0.7 0.7) (thickness 0.15)) (justify left bottom))
    )
    (fp_line (start -0.3 -0.3) (end 0.3 -0.3)
      (stroke (width 0.15) (type solid)) (layer "F.SilkS"))
    (fp_line (start -0.3 0.3) (end 0.3 0.3)
      (stroke (width 0.15) (type solid)) (layer "F.SilkS"))
    (fp_rect (start -1.25 -0.7) (end 1.25 0.7)
      (stroke (width 0.05) (type solid)) (fill none) (layer "F.CrtYd"))
    (fp_rect (start -0.8 -0.4) (end 0.8 0.4)
      (stroke (width 0.15) (type solid)) (fill none) (layer "F.Fab"))
    (pad "1" smd roundrect (at -0.7 0 90) (size 0.6 0.8) (layers "F.Cu" "F.Paste" "F.Mask") (roundrect_rratio 0.2)
      (net 70 "Net-(C43-Pad2)") (pintype "passive"))
    (pad "2" smd roundrect (at 0.7 0 90) (size 0.6 0.8) (layers "F.Cu" "F.Paste" "F.Mask") (roundrect_rratio 0.2)
      (net 3 "GNDA") (pintype "passive"))
  )
	(footprint "sdi-mipi-bridge-footprints:C_0402_1005Metric" (layer "F.Cu")
    (at 113.82 113.9)
    (descr "Capacitor SMD 0402")
    (tags "capacitor SMD 0402")
    (property "Author" "Antmicro")
    (property "Dielectric" "")
    (property "License" "Apache-2.0")
    (property "MPN" "C1005X6S1A105K050BC")
    (property "Manufacturer" "TDK")
    (property "Sheetfile" "sdi-mipi-bridge.kicad_sch")
    (property "Sheetname" "")
    (property "Val" "1u")
    (property "Voltage" "")
    (property "ki_description" " ")
    (attr smd)
    (fp_text reference "C56" (at -7.22 -0.85) (layer "F.SilkS")
        (effects (font (size 0.65 0.65) (thickness 0.15)) (justify left bottom))
    )
    (fp_text value "C_1u_0402" (at 0 1.4) (layer "F.Fab") hide
        (effects (font (size 0.7 0.7) (thickness 0.15)) (justify left bottom))
    )
    (fp_text user "Author: Antmicro" (at -0.932 4.17) (layer "F.Fab") hide
        (effects (font (size 0.7 0.7) (thickness 0.15)) (justify left bottom))
    )
    (fp_text user "License: Apache-2.0" (at -0.932 5.17) (layer "F.Fab") hide
        (effects (font (size 0.7 0.7) (thickness 0.15)) (justify left bottom))
    )
    (fp_text user "${REFERENCE}" (at -0.932 3.168) (layer "F.Fab") hide
        (effects (font (size 0.7 0.7) (thickness 0.15)) (justify left bottom))
    )
    (fp_rect (start -0.94 -0.47) (end 0.94 0.47)
      (stroke (width 0.05) (type solid)) (fill none) (layer "F.CrtYd"))
    (fp_rect (start -0.499 -0.249) (end 0.499 0.249)
      (stroke (width 0.15) (type solid)) (fill none) (layer "F.Fab"))
    (pad "1" smd roundrect (at -0.484 0) (size 0.59 0.64) (layers "F.Cu" "F.Paste" "F.Mask") (roundrect_rratio 0.25)
      (net 142 "Net-(C56-Pad1)") (pintype "passive"))
    (pad "2" smd roundrect (at 0.484 0) (size 0.59 0.64) (layers "F.Cu" "F.Paste" "F.Mask") (roundrect_rratio 0.25)
      (net 92 "/SDI_N") (pintype "passive"))
  )
	(footprint "sdi-mipi-bridge-footprints:C_0603_1608Metric" (layer "F.Cu")
    (at 109.5 112.2 -90)
    (descr "Capacitor SMD 0603")
    (tags "capacitor 0603")
    (property "Author" "Antmicro")
    (property "Dielectric" "")
    (property "License" "Apache-2.0")
    (property "MPN" "C0603C622J5GACAUTO")
    (property "Manufacturer" "KEMET")
    (property "Sheetfile" "sdi-mipi-bridge.kicad_sch")
    (property "Sheetname" "")
    (property "Val" "6n2")
    (property "Voltage" "")
    (property "ki_description" " ")
    (attr smd)
    (fp_text reference "C43" (at -3.4 -0.3 -90) (layer "F.SilkS")
        (effects (font (size 0.65 0.65) (thickness 0.15)) (justify right bottom))
    )
    (fp_text value "C_6n2_0603" (at 0 1.6 90) (layer "F.Fab") hide
        (effects (font (size 0.7 0.7) (thickness 0.15)) (justify right bottom))
    )
    (fp_text user "License: Apache-2.0" (at -1.682 5.895 90) (layer "F.Fab") hide
        (effects (font (size 0.7 0.7) (thickness 0.15)) (justify right bottom))
    )
    (fp_text user "${REFERENCE}" (at -1.682 3.895 90) (layer "F.Fab") hide
        (effects (font (size 0.7 0.7) (thickness 0.15)) (justify right bottom))
    )
    (fp_text user "Author: Antmicro" (at -1.682 4.894 90) (layer "F.Fab") hide
        (effects (font (size 0.7 0.7) (thickness 0.15)) (justify right bottom))
    )
    (fp_line (start -0.3 -0.3) (end 0.3 -0.3)
      (stroke (width 0.15) (type solid)) (layer "F.SilkS"))
    (fp_line (start -0.3 0.3) (end 0.3 0.3)
      (stroke (width 0.15) (type solid)) (layer "F.SilkS"))
    (fp_rect (start -1.24 -0.7) (end 1.24 0.7)
      (stroke (width 0.05) (type solid)) (fill none) (layer "F.CrtYd"))
    (fp_rect (start -0.8 -0.4) (end 0.8 0.4)
      (stroke (width 0.15) (type solid)) (fill none) (layer "F.Fab"))
    (pad "1" smd roundrect (at -0.7 0 270) (size 0.6 0.8) (layers "F.Cu" "F.Paste" "F.Mask") (roundrect_rratio 0.2)
      (net 69 "Net-(C43-Pad1)") (pintype "passive"))
    (pad "2" smd roundrect (at 0.7 0 270) (size 0.6 0.8) (layers "F.Cu" "F.Paste" "F.Mask") (roundrect_rratio 0.2)
      (net 70 "Net-(C43-Pad2)") (pintype "passive"))
  )
	(footprint "sdi-mipi-bridge-footprints:R_0402_1005Metric" (layer "F.Cu")
    (at 112.84 114.95 180)
    (descr "Resistor SMD 0402")
    (tags "resistor SMD 0402")
    (property "Author" "Antmicro")
    (property "License" "Apache-2.0")
    (property "MPN" "CR0402-FX-37R4GLF")
    (property "Manufacturer" "Bourns")
    (property "Sheetfile" "sdi-mipi-bridge.kicad_sch")
    (property "Sheetname" "")
    (property "Tolerance" "1%")
    (property "Val" "37R4")
    (property "ki_description" "37R4 resistor in 0402 package with 1% tolerance")
    (attr smd)
    (fp_text reference "R29" (at 6.74 0.85 180) (layer "F.SilkS")
        (effects (font (size 0.65 0.65) (thickness 0.15)) (justify bottom))
    )
    (fp_text value "R_37R4_0402" (at 0 1.4 180) (layer "F.Fab") hide
        (effects (font (size 0.7 0.7) (thickness 0.15)) (justify left bottom))
    )
    (fp_text user "License: Apache-2.0" (at -0.95 5.169 180) (layer "F.Fab") hide
        (effects (font (size 0.7 0.7) (thickness 0.15)) (justify left bottom))
    )
    (fp_text user "Author: Antmicro" (at -0.95 4.169 180) (layer "F.Fab") hide
        (effects (font (size 0.7 0.7) (thickness 0.15)) (justify left bottom))
    )
    (fp_text user "${REFERENCE}" (at -0.95 3.168 180) (layer "F.Fab") hide
        (effects (font (size 0.7 0.7) (thickness 0.15)) (justify left bottom))
    )
    (fp_rect (start -0.93 -0.47) (end 0.93 0.47)
      (stroke (width 0.05) (type solid)) (fill none) (layer "F.CrtYd"))
    (fp_rect (start -0.5 -0.25) (end 0.5 0.25)
      (stroke (width 0.15) (type solid)) (fill none) (layer "F.Fab"))
    (pad "1" smd roundrect (at -0.485 0 180) (size 0.59 0.64) (layers "F.Cu" "F.Paste" "F.Mask") (roundrect_rratio 0.25)
      (net 142 "Net-(C56-Pad1)") (pintype "passive"))
    (pad "2" smd roundrect (at 0.485 0 180) (size 0.59 0.64) (layers "F.Cu" "F.Paste" "F.Mask") (roundrect_rratio 0.25)
      (net 3 "GNDA") (pintype "passive"))
  )
	(footprint "sdi-mipi-bridge-footprints:QFN-16_1EP_4x4mm_P0.65mm" (layer "F.Cu")
    (at 111.9 120.9 180)
    (property "Author" "Antmicro")
    (property "License" "Apache-2.0")
    (property "MPN" "GS2988-INE3")
    (property "Manufacturer" "Semtech")
    (property "Sheetfile" "sdi-mipi-bridge.kicad_sch")
    (property "Sheetname" "")
    (property "ki_description" "LVPECL/CML Cable driver 3Gb/s")
    (property "ki_keywords" "LVPECL/CML Cable driver 3Gb/s")
    (attr smd)
    (fp_text reference "U3" (at -2.4 -1.9 180) (layer "F.SilkS")
        (effects (font (size 0.65 0.65) (thickness 0.15)) (justify left bottom))
    )
    (fp_text value "GS2988" (at 0 3.3 180) (layer "F.Fab") hide
        (effects (font (size 0.7 0.7) (thickness 0.15)) (justify left bottom))
    )
    (fp_text user "License: Apache-2.0" (at -2.35 7.999 180) (layer "F.Fab") hide
        (effects (font (size 0.7 0.7) (thickness 0.15)) (justify left bottom))
    )
    (fp_text user "Author: Antmicro" (at -2.35 6.799 180) (layer "F.Fab") hide
        (effects (font (size 0.7 0.7) (thickness 0.15)) (justify left bottom))
    )
    (fp_text user "${REFERENCE}" (at -2.35 5.599 180) (layer "F.Fab") hide
        (effects (font (size 0.7 0.7) (thickness 0.15)) (justify left bottom))
    )
    (fp_line (start -2.101 1.398) (end -2.101 2.1)
      (stroke (width 0.15) (type solid)) (layer "F.SilkS"))
    (fp_line (start -2.101 2.1) (end -1.5 2.1)
      (stroke (width 0.15) (type solid)) (layer "F.SilkS"))
    (fp_line (start -2.1 -2.1) (end -2.101 -1.4)
      (stroke (width 0.15) (type solid)) (layer "F.SilkS"))
    (fp_line (start -1.4 -2.1) (end -2.1 -2.1)
      (stroke (width 0.15) (type solid)) (layer "F.SilkS"))
    (fp_line (start 1.499 -2.101) (end 2.1 -2.101)
      (stroke (width 0.15) (type solid)) (layer "F.SilkS"))
    (fp_line (start 1.499 2.1) (end 2.1 2.1)
      (stroke (width 0.15) (type solid)) (layer "F.SilkS"))
    (fp_line (start 2.1 -2.101) (end 2.1 -1.401)
      (stroke (width 0.15) (type solid)) (layer "F.SilkS"))
    (fp_line (start 2.1 2.1) (end 2.1 1.398)
      (stroke (width 0.15) (type solid)) (layer "F.SilkS"))
    (fp_circle (center -2.35 -1.4) (end -2.3 -1.4)
      (stroke (width 0.15) (type solid)) (fill solid) (layer "F.SilkS"))
    (fp_rect (start -2.35 -2.35) (end 2.35 2.35)
      (stroke (width 0.05) (type solid)) (fill none) (layer "F.CrtYd"))
    (fp_line (start -1.5 -2) (end -2 -1.5)
      (stroke (width 0.15) (type solid)) (layer "F.Fab"))
    (fp_rect (start 2 2) (end -2 -2)
      (stroke (width 0.15) (type solid)) (fill none) (layer "F.Fab"))
    (pad "1" smd rect (at -1.901 -0.975 180) (size 0.8 0.4) (layers "F.Cu" "F.Paste" "F.Mask")
      (net 94 "/SDO_P") (pinfunction "DDI+") (pintype "input"))
    (pad "2" smd rect (at -1.901 -0.327 180) (size 0.8 0.4) (layers "F.Cu" "F.Paste" "F.Mask")
      (net 93 "/SDO_N") (pinfunction "DDI-") (pintype "input"))
    (pad "3" smd rect (at -1.901 0.325 180) (size 0.8 0.4) (layers "F.Cu" "F.Paste" "F.Mask")
      (net 3 "GNDA") (pinfunction "V_{EE}") (pintype "power_in"))
    (pad "4" smd rect (at -1.901 0.973 180) (size 0.8 0.4) (layers "F.Cu" "F.Paste" "F.Mask")
      (net 67 "Net-(U3-RSET)") (pinfunction "RSET") (pintype "passive"))
    (pad "5" smd rect (at -0.975 1.898 180) (size 0.4 0.8) (layers "F.Cu" "F.Paste" "F.Mask")
      (net 134 "unconnected-(U3-NC-Pad5)") (pinfunction "NC") (pintype "no_connect"))
    (pad "6" smd rect (at -0.327 1.898 180) (size 0.4 0.8) (layers "F.Cu" "F.Paste" "F.Mask")
      (net 55 "/SDO_EN_DIS") (pinfunction "~{DISABLE}") (pintype "input"))
    (pad "7" smd rect (at 0.325 1.898 180) (size 0.4 0.8) (layers "F.Cu" "F.Paste" "F.Mask")
      (net 135 "unconnected-(U3-NC-Pad7)") (pinfunction "NC") (pintype "no_connect"))
    (pad "8" smd rect (at 0.973 1.898 180) (size 0.4 0.8) (layers "F.Cu" "F.Paste" "F.Mask")
      (net 137 "unconnected-(U3-NC-Pad8)") (pinfunction "NC") (pintype "no_connect"))
    (pad "9" smd rect (at 1.898 0.973 180) (size 0.8 0.4) (layers "F.Cu" "F.Paste" "F.Mask")
      (net 57 "VDD") (pinfunction "V_{CC}") (pintype "power_in"))
    (pad "10" smd rect (at 1.898 0.325 180) (size 0.8 0.4) (layers "F.Cu" "F.Paste" "F.Mask")
      (net 3 "GNDA") (pinfunction "SD/~{HD}") (pintype "input"))
    (pad "11" smd rect (at 1.898 -0.327 180) (size 0.8 0.4) (layers "F.Cu" "F.Paste" "F.Mask")
      (net 29 "Net-(U3-SDO-)") (pinfunction "SDO-") (pintype "output"))
    (pad "12" smd rect (at 1.898 -0.975 180) (size 0.8 0.4) (layers "F.Cu" "F.Paste" "F.Mask")
      (net 27 "Net-(U3-SDO+)") (pinfunction "SDO+") (pintype "output"))
    (pad "13" smd rect (at 0.973 -1.901 180) (size 0.4 0.8) (layers "F.Cu" "F.Paste" "F.Mask")
      (net 138 "unconnected-(U3-NC-Pad13)") (pinfunction "NC") (pintype "no_connect"))
    (pad "14" smd rect (at 0.325 -1.901 180) (size 0.4 0.8) (layers "F.Cu" "F.Paste" "F.Mask")
      (net 131 "Net-(U3-~{OSP})") (pinfunction "~{OSP}") (pintype "output"))
    (pad "15" smd rect (at -0.327 -1.901 180) (size 0.4 0.8) (layers "F.Cu" "F.Paste" "F.Mask")
      (net 139 "unconnected-(U3-NC-Pad15)") (pinfunction "NC") (pintype "no_connect"))
    (pad "16" smd rect (at -0.975 -1.901 180) (size 0.4 0.8) (layers "F.Cu" "F.Paste" "F.Mask")
      (net 73 "Net-(U3-~{EQ_EN})") (pinfunction "~{EQ_EN}") (pintype "input"))
    (pad "17" smd rect (at 0 0 180) (size 2.3 2.3) (layers "F.Cu" "F.Paste" "F.Mask")
      (net 3 "GNDA") (pinfunction "EP") (pintype "passive"))
  )
	(footprint "sdi-mipi-bridge-footprints:Testpoint_smd_1mm" (layer "F.Cu")
    (at 111.61 124.19 180)
    (property "Author" "Antmicro")
    (property "License" "Apache-2.0")
    (property "MPN" "")
    (property "Manufacturer" "")
    (property "Sheetfile" "sdi-mipi-bridge.kicad_sch")
    (property "Sheetname" "")
    (property "ki_description" "Test Point 1mm")
    (attr smd)
    (fp_text reference "TP18" (at -1.39 -1.31) (layer "F.SilkS")
        (effects (font (size 0.65 0.65) (thickness 0.15)) (justify right bottom))
    )
    (fp_text value "TP_1mm_SMD" (at 0 1.4) (layer "F.Fab") hide
        (effects (font (size 0.7 0.7) (thickness 0.15)) (justify right bottom))
    )
    (fp_text user "${REFERENCE}" (at -0.5 2.8) (layer "F.Fab") hide
        (effects (font (size 0.7 0.7) (thickness 0.15)) (justify right bottom))
    )
    (fp_text user "Author: Antmicro" (at -0.5 4) (layer "F.Fab") hide
        (effects (font (size 0.7 0.7) (thickness 0.15)) (justify right bottom))
    )
    (fp_text user "License: Apache-2.0" (at -0.5 5.2) (layer "F.Fab") hide
        (effects (font (size 0.7 0.7) (thickness 0.15)) (justify right bottom))
    )
    (pad "1" smd circle (at 0 0 180) (size 1 1) (layers "F.Cu" "F.Mask")
      (net 131 "Net-(U3-~{OSP})") (pinfunction "1") (pintype "passive"))
  )
	(footprint "sdi-mipi-bridge-footprints:C_0402_1005Metric" (layer "F.Cu")
    (at 106.95 122.8 90)
    (descr "Capacitor SMD 0402")
    (tags "capacitor SMD 0402")
    (property "Author" "Antmicro")
    (property "Dielectric" "")
    (property "License" "Apache-2.0")
    (property "MPN" "GRM155R61A475MEAAD")
    (property "Manufacturer" "Murata")
    (property "Sheetfile" "sdi-mipi-bridge.kicad_sch")
    (property "Sheetname" "")
    (property "Val" "4u7")
    (property "Voltage" "")
    (property "ki_description" " ")
    (attr smd)
    (fp_text reference "C23" (at -10.1 1.65 90) (layer "F.SilkS")
        (effects (font (size 0.65 0.65) (thickness 0.15)) (justify left bottom))
    )
    (fp_text value "C_4u7_0402" (at 0 1.4 90) (layer "F.Fab") hide
        (effects (font (size 0.7 0.7) (thickness 0.15)) (justify left bottom))
    )
    (fp_text user "License: Apache-2.0" (at -0.932 5.17 90) (layer "F.Fab") hide
        (effects (font (size 0.7 0.7) (thickness 0.15)) (justify left bottom))
    )
    (fp_text user "Author: Antmicro" (at -0.932 4.17 90) (layer "F.Fab") hide
        (effects (font (size 0.7 0.7) (thickness 0.15)) (justify left bottom))
    )
    (fp_text user "${REFERENCE}" (at -0.932 3.168 90) (layer "F.Fab") hide
        (effects (font (size 0.7 0.7) (thickness 0.15)) (justify left bottom))
    )
    (fp_rect (start -0.94 -0.47) (end 0.94 0.47)
      (stroke (width 0.05) (type solid)) (fill none) (layer "F.CrtYd"))
    (fp_rect (start -0.499 -0.249) (end 0.499 0.249)
      (stroke (width 0.15) (type solid)) (fill none) (layer "F.Fab"))
    (pad "1" smd roundrect (at -0.484 0 90) (size 0.59 0.64) (layers "F.Cu" "F.Paste" "F.Mask") (roundrect_rratio 0.25)
      (net 65 "Net-(C23-Pad1)") (pintype "passive"))
    (pad "2" smd roundrect (at 0.484 0 90) (size 0.59 0.64) (layers "F.Cu" "F.Paste" "F.Mask") (roundrect_rratio 0.25)
      (net 27 "Net-(U3-SDO+)") (pintype "passive"))
  )
	(footprint "sdi-mipi-bridge-footprints:R_0603_1608Metric" (layer "F.Cu")
    (at 107.65 125.15 180)
    (descr "Resistor SMD 0603")
    (tags "resistor SMD 0603")
    (property "Author" "Antmicro")
    (property "License" "Apache-2.0")
    (property "MPN" "CR0603-FX-75R0ELF")
    (property "Manufacturer" "Bourns")
    (property "Sheetfile" "sdi-mipi-bridge.kicad_sch")
    (property "Sheetname" "")
    (property "Tolerance" "1%")
    (property "Val" "75R")
    (property "ki_description" "75R resistor in 0603 package with 1% tolerance")
    (attr smd)
    (fp_text reference "R20" (at -0.15 -9.35 180) (layer "F.SilkS")
        (effects (font (size 0.65 0.65) (thickness 0.15)) (justify left bottom))
    )
    (fp_text value "R_75R_0603" (at 0 1.6 180) (layer "F.Fab") hide
        (effects (font (size 0.7 0.7) (thickness 0.15)) (justify left bottom))
    )
    (fp_text user "${REFERENCE}" (at -1.25 3.898 180) (layer "F.Fab") hide
        (effects (font (size 0.7 0.7) (thickness 0.15)) (justify left bottom))
    )
    (fp_text user "License: Apache-2.0" (at -1.25 5.9 180) (layer "F.Fab") hide
        (effects (font (size 0.7 0.7) (thickness 0.15)) (justify left bottom))
    )
    (fp_text user "Author: Antmicro" (at -1.25 4.9 180) (layer "F.Fab") hide
        (effects (font (size 0.7 0.7) (thickness 0.15)) (justify left bottom))
    )
    (fp_line (start -0.3 -0.3) (end 0.3 -0.3)
      (stroke (width 0.15) (type solid)) (layer "F.SilkS"))
    (fp_line (start -0.3 0.3) (end 0.3 0.3)
      (stroke (width 0.15) (type solid)) (layer "F.SilkS"))
    (fp_rect (start -1.25 -0.7) (end 1.25 0.7)
      (stroke (width 0.05) (type solid)) (fill none) (layer "F.CrtYd"))
    (fp_rect (start -0.8 -0.4) (end 0.8 0.4)
      (stroke (width 0.15) (type solid)) (fill none) (layer "F.Fab"))
    (pad "1" smd roundrect (at -0.7 0 180) (size 0.6 0.8) (layers "F.Cu" "F.Paste" "F.Mask") (roundrect_rratio 0.2)
      (net 3 "GNDA") (pintype "passive"))
    (pad "2" smd roundrect (at 0.7 0 180) (size 0.6 0.8) (layers "F.Cu" "F.Paste" "F.Mask") (roundrect_rratio 0.2)
      (net 65 "Net-(C23-Pad1)") (pintype "passive"))
  )
)
